(kicad_pcb
	(version 20260206)
	(generator "pcbnew")
	(generator_version "10.0")
	(general
		(thickness 1.6)
		(legacy_teardrops no)
	)
	(paper "A4")
	(title_block
		(title "04192023_DAF0TMB3IC0_F0TG_MB_C_brd_V02_OCP.brd")
		(comment 1 "Grand Teton / footprints 3865-3871 of 8354")
	)
	(layers
		(0 "F.Cu" signal "TOP")
		(4 "In1.Cu" signal "GND")
		(6 "In2.Cu" signal "IN1")
		(8 "In3.Cu" signal "GND1")
		(10 "In4.Cu" signal "IN2")
		(12 "In5.Cu" signal "GND2")
		(14 "In6.Cu" signal "IN3")
		(16 "In7.Cu" signal "GND3")
		(18 "In8.Cu" signal "VCC")
		(20 "In9.Cu" signal "VCC1")
		(22 "In10.Cu" signal "GND4")
		(24 "In11.Cu" signal "IN4")
		(26 "In12.Cu" signal "GND5")
		(28 "In13.Cu" signal "IN5")
		(30 "In14.Cu" signal "GND6")
		(32 "In15.Cu" signal "IN6")
		(34 "In16.Cu" signal "GND7")
		(2 "B.Cu" signal "BOTTOM")
		(9 "F.Adhes" user "F.Adhesive")
		(11 "B.Adhes" user "B.Adhesive")
		(13 "F.Paste" user "Package Geometry/Pastemask Top")
		(15 "B.Paste" user "Package Geometry/Pastemask Bottom")
		(5 "F.SilkS" user "Ref Des/Silkscreen Top")
		(7 "B.SilkS" user "Ref Des/Silkscreen Bottom")
		(1 "F.Mask" user "Board Geometry/Soldermask Top")
		(3 "B.Mask" user "Board Geometry/Soldermask Bottom")
		(17 "Dwgs.User" user "User.Drawings")
		(19 "Cmts.User" user "User.Comments")
		(21 "Eco1.User" user "User.Eco1")
		(23 "Eco2.User" user "User.Eco2")
		(25 "Edge.Cuts" user "Board Geometry/Outline")
		(27 "Margin" user)
		(31 "F.CrtYd" user "Package Geometry/Place Bound Top")
		(29 "B.CrtYd" user "Package Geometry/Place Bound Bottom")
		(35 "F.Fab" user "Ref Des/Assembly Top")
		(33 "B.Fab" user "Ref Des/Assembly Bottom")
	)
	(footprint ""
		(layer "F.Cu")
		(at 171.776644 -128.24333)
		(property "Reference" "R6850"
			(at 0 0 0)
			(layer "F.SilkS")
			(hide yes)
			(effects
				(font
					(size 1.27 1.27)
				)
			)
		)
		(property "Value" ""
			(at 0 0 0)
			(layer "F.Fab")
			(effects
				(font
					(size 1.27 1.27)
				)
			)
		)
		(duplicate_pad_numbers_are_jumpers no)
		(fp_line
			(start -0.7874 -0.4064)
			(end 0.7874 -0.4064)
			(stroke
				(width 0.1524)
				(type default)
			)
			(layer "F.SilkS")
		)
		(fp_line
			(start -0.7874 0.4064)
			(end -0.7874 -0.4064)
			(stroke
				(width 0.1524)
				(type default)
			)
			(layer "F.SilkS")
		)
		(fp_line
			(start 0.7874 -0.4064)
			(end 0.7874 0.4064)
			(stroke
				(width 0.1524)
				(type default)
			)
			(layer "F.SilkS")
		)
		(fp_line
			(start 0.7874 0.4064)
			(end -0.7874 0.4064)
			(stroke
				(width 0.1524)
				(type default)
			)
			(layer "F.SilkS")
		)
		(fp_line
			(start -0.67945 -0.305054)
			(end -0.12065 -0.305054)
			(stroke
				(width 0.1)
				(type default)
			)
			(layer "F.Fab")
		)
		(fp_line
			(start -0.67945 0.3048)
			(end -0.67945 -0.305054)
			(stroke
				(width 0.1)
				(type default)
			)
			(layer "F.Fab")
		)
		(fp_line
			(start -0.12065 -0.305054)
			(end -0.12065 -0.2794)
			(stroke
				(width 0.1)
				(type default)
			)
			(layer "F.Fab")
		)
		(fp_line
			(start -0.12065 -0.2794)
			(end 0.12065 -0.2794)
			(stroke
				(width 0.1)
				(type default)
			)
			(layer "F.Fab")
		)
		(fp_line
			(start -0.12065 0.2794)
			(end -0.12065 0.3048)
			(stroke
				(width 0.1)
				(type default)
			)
			(layer "F.Fab")
		)
		(fp_line
			(start -0.12065 0.3048)
			(end -0.67945 0.3048)
			(stroke
				(width 0.1)
				(type default)
			)
			(layer "F.Fab")
		)
		(fp_line
			(start 0.120396 0.2794)
			(end -0.12065 0.2794)
			(stroke
				(width 0.1)
				(type default)
			)
			(layer "F.Fab")
		)
		(fp_line
			(start 0.120396 0.3048)
			(end 0.120396 0.2794)
			(stroke
				(width 0.1)
				(type default)
			)
			(layer "F.Fab")
		)
		(fp_line
			(start 0.12065 -0.3048)
			(end 0.67945 -0.3048)
			(stroke
				(width 0.1)
				(type default)
			)
			(layer "F.Fab")
		)
		(fp_line
			(start 0.12065 -0.2794)
			(end 0.12065 -0.3048)
			(stroke
				(width 0.1)
				(type default)
			)
			(layer "F.Fab")
		)
		(fp_line
			(start 0.67945 -0.3048)
			(end 0.67945 0.3048)
			(stroke
				(width 0.1)
				(type default)
			)
			(layer "F.Fab")
		)
		(fp_line
			(start 0.67945 0.3048)
			(end 0.120396 0.3048)
			(stroke
				(width 0.1)
				(type default)
			)
			(layer "F.Fab")
		)
		(pad "1" smd circle
			(at -0.40005 0)
			(size 0 0)
			(layers "F.Cu" "F.Mask" "F.Paste")
			(net "P1V8_RETIMER_CPU0_EN")
		)
		(pad "2" smd circle
			(at 0.40005 0)
			(size 0 0)
			(layers "F.Cu" "F.Mask" "F.Paste")
			(net "P1V8_RETIMER_CPU0_R_EN")
		)
	)
	(footprint ""
		(layer "F.Cu")
		(at 120.396 -431.038 180)
		(property "Reference" "R3448"
			(at 0 0 180)
			(layer "F.SilkS")
			(hide yes)
			(effects
				(font
					(size 1.27 1.27)
				)
			)
		)
		(property "Value" ""
			(at 0 0 180)
			(layer "F.Fab")
			(effects
				(font
					(size 1.27 1.27)
				)
			)
		)
		(duplicate_pad_numbers_are_jumpers no)
		(fp_line
			(start 0.7874 0.4064)
			(end -0.7874 0.4064)
			(stroke
				(width 0.1524)
				(type default)
			)
			(layer "F.SilkS")
		)
		(fp_line
			(start 0.7874 -0.4064)
			(end 0.7874 0.4064)
			(stroke
				(width 0.1524)
				(type default)
			)
			(layer "F.SilkS")
		)
		(fp_line
			(start -0.7874 0.4064)
			(end -0.7874 -0.4064)
			(stroke
				(width 0.1524)
				(type default)
			)
			(layer "F.SilkS")
		)
		(fp_line
			(start -0.7874 -0.4064)
			(end 0.7874 -0.4064)
			(stroke
				(width 0.1524)
				(type default)
			)
			(layer "F.SilkS")
		)
		(fp_line
			(start 0.67945 0.3048)
			(end 0.120396 0.3048)
			(stroke
				(width 0.1)
				(type default)
			)
			(layer "F.Fab")
		)
		(fp_line
			(start 0.67945 -0.3048)
			(end 0.67945 0.3048)
			(stroke
				(width 0.1)
				(type default)
			)
			(layer "F.Fab")
		)
		(fp_line
			(start 0.12065 -0.2794)
			(end 0.12065 -0.3048)
			(stroke
				(width 0.1)
				(type default)
			)
			(layer "F.Fab")
		)
		(fp_line
			(start 0.12065 -0.3048)
			(end 0.67945 -0.3048)
			(stroke
				(width 0.1)
				(type default)
			)
			(layer "F.Fab")
		)
		(fp_line
			(start 0.120396 0.3048)
			(end 0.120396 0.2794)
			(stroke
				(width 0.1)
				(type default)
			)
			(layer "F.Fab")
		)
		(fp_line
			(start 0.120396 0.2794)
			(end -0.12065 0.2794)
			(stroke
				(width 0.1)
				(type default)
			)
			(layer "F.Fab")
		)
		(fp_line
			(start -0.12065 0.3048)
			(end -0.67945 0.3048)
			(stroke
				(width 0.1)
				(type default)
			)
			(layer "F.Fab")
		)
		(fp_line
			(start -0.12065 0.2794)
			(end -0.12065 0.3048)
			(stroke
				(width 0.1)
				(type default)
			)
			(layer "F.Fab")
		)
		(fp_line
			(start -0.12065 -0.2794)
			(end 0.12065 -0.2794)
			(stroke
				(width 0.1)
				(type default)
			)
			(layer "F.Fab")
		)
		(fp_line
			(start -0.12065 -0.305054)
			(end -0.12065 -0.2794)
			(stroke
				(width 0.1)
				(type default)
			)
			(layer "F.Fab")
		)
		(fp_line
			(start -0.67945 0.3048)
			(end -0.67945 -0.305054)
			(stroke
				(width 0.1)
				(type default)
			)
			(layer "F.Fab")
		)
		(fp_line
			(start -0.67945 -0.305054)
			(end -0.12065 -0.305054)
			(stroke
				(width 0.1)
				(type default)
			)
			(layer "F.Fab")
		)
		(pad "1" smd circle
			(at -0.40005 0 180)
			(size 0 0)
			(layers "F.Cu" "F.Mask" "F.Paste")
			(net "P3V3_AUX")
		)
		(pad "2" smd circle
			(at 0.40005 0 180)
			(size 0 0)
			(layers "F.Cu" "F.Mask" "F.Paste")
			(net "GPU_FPGA_BOOT_EN")
		)
	)
	(footprint ""
		(layer "F.Cu")
		(at 124.058426 -408.517344 -90)
		(property "Reference" "C6700"
			(at 0 0 270)
			(layer "F.SilkS")
			(hide yes)
			(effects
				(font
					(size 1.27 1.27)
				)
			)
		)
		(property "Value" ""
			(at 0 0 270)
			(layer "F.Fab")
			(effects
				(font
					(size 1.27 1.27)
				)
			)
		)
		(duplicate_pad_numbers_are_jumpers no)
		(fp_line
			(start -0.299974 0.150114)
			(end -0.299974 -0.150114)
			(stroke
				(width 0.1)
				(type default)
			)
			(layer "F.Fab")
		)
		(fp_line
			(start 0.299974 0.150114)
			(end -0.299974 0.150114)
			(stroke
				(width 0.1)
				(type default)
			)
			(layer "F.Fab")
		)
		(fp_line
			(start -0.299974 -0.150114)
			(end 0.299974 -0.150114)
			(stroke
				(width 0.1)
				(type default)
			)
			(layer "F.Fab")
		)
		(fp_line
			(start 0.299974 -0.150114)
			(end 0.299974 0.150114)
			(stroke
				(width 0.1)
				(type default)
			)
			(layer "F.Fab")
		)
		(pad "1" smd rect
			(at -0.2667 0 270)
			(size 0.3048 0.381)
			(layers "F.Cu" "F.Mask" "F.Paste")
			(net "P5E_CPU1_P2_TX_BUF_C_DN<3>")
		)
		(pad "2" smd rect
			(at 0.2667 0 270)
			(size 0.3048 0.381)
			(layers "F.Cu" "F.Mask" "F.Paste")
			(net "P5E_CPU1_P2_TX_BUF_DN<3>")
		)
	)
	(footprint ""
		(layer "F.Cu")
		(at 142.893542 -384.66268)
		(property "Reference" "R876"
			(at 0 0 0)
			(layer "F.SilkS")
			(hide yes)
			(effects
				(font
					(size 1.27 1.27)
				)
			)
		)
		(property "Value" ""
			(at 0 0 0)
			(layer "F.Fab")
			(effects
				(font
					(size 1.27 1.27)
				)
			)
		)
		(duplicate_pad_numbers_are_jumpers no)
		(fp_line
			(start -0.32512 -0.175006)
			(end 0.32512 -0.175006)
			(stroke
				(width 0.1)
				(type default)
			)
			(layer "F.Fab")
		)
		(fp_line
			(start -0.32512 0.175006)
			(end -0.32512 -0.175006)
			(stroke
				(width 0.1)
				(type default)
			)
			(layer "F.Fab")
		)
		(fp_line
			(start 0.32512 -0.175006)
			(end 0.32512 0.175006)
			(stroke
				(width 0.1)
				(type default)
			)
			(layer "F.Fab")
		)
		(fp_line
			(start 0.32512 0.175006)
			(end -0.32512 0.175006)
			(stroke
				(width 0.1)
				(type default)
			)
			(layer "F.Fab")
		)
		(pad "1" smd rect
			(at -0.2667 0)
			(size 0.3048 0.381)
			(layers "F.Cu" "F.Mask" "F.Paste")
			(net "GPIO3_RT_CPU1_P2")
		)
		(pad "2" smd rect
			(at 0.2667 0 180)
			(size 0.3048 0.381)
			(layers "F.Cu" "F.Mask" "F.Paste")
			(net "GND")
		)
	)
	(footprint ""
		(layer "F.Cu")
		(at 189.366398 -426.375068 -90)
		(property "Reference" "R9013"
			(at 0 0 270)
			(layer "F.SilkS")
			(hide yes)
			(effects
				(font
					(size 1.27 1.27)
				)
			)
		)
		(property "Value" ""
			(at 0 0 270)
			(layer "F.Fab")
			(effects
				(font
					(size 1.27 1.27)
				)
			)
		)
		(duplicate_pad_numbers_are_jumpers no)
		(fp_line
			(start -0.7874 0.4064)
			(end -0.7874 -0.4064)
			(stroke
				(width 0.1524)
				(type default)
			)
			(layer "F.SilkS")
		)
		(fp_line
			(start 0.7874 0.4064)
			(end -0.7874 0.4064)
			(stroke
				(width 0.1524)
				(type default)
			)
			(layer "F.SilkS")
		)
		(fp_line
			(start -0.7874 -0.4064)
			(end 0.7874 -0.4064)
			(stroke
				(width 0.1524)
				(type default)
			)
			(layer "F.SilkS")
		)
		(fp_line
			(start 0.7874 -0.4064)
			(end 0.7874 0.4064)
			(stroke
				(width 0.1524)
				(type default)
			)
			(layer "F.SilkS")
		)
		(fp_line
			(start -0.67945 0.3048)
			(end -0.67945 -0.305054)
			(stroke
				(width 0.1)
				(type default)
			)
			(layer "F.Fab")
		)
		(fp_line
			(start -0.12065 0.3048)
			(end -0.67945 0.3048)
			(stroke
				(width 0.1)
				(type default)
			)
			(layer "F.Fab")
		)
		(fp_line
			(start 0.120396 0.3048)
			(end 0.120396 0.2794)
			(stroke
				(width 0.1)
				(type default)
			)
			(layer "F.Fab")
		)
		(fp_line
			(start 0.67945 0.3048)
			(end 0.120396 0.3048)
			(stroke
				(width 0.1)
				(type default)
			)
			(layer "F.Fab")
		)
		(fp_line
			(start -0.12065 0.2794)
			(end -0.12065 0.3048)
			(stroke
				(width 0.1)
				(type default)
			)
			(layer "F.Fab")
		)
		(fp_line
			(start 0.120396 0.2794)
			(end -0.12065 0.2794)
			(stroke
				(width 0.1)
				(type default)
			)
			(layer "F.Fab")
		)
		(fp_line
			(start -0.12065 -0.2794)
			(end 0.12065 -0.2794)
			(stroke
				(width 0.1)
				(type default)
			)
			(layer "F.Fab")
		)
		(fp_line
			(start 0.12065 -0.2794)
			(end 0.12065 -0.3048)
			(stroke
				(width 0.1)
				(type default)
			)
			(layer "F.Fab")
		)
		(fp_line
			(start 0.12065 -0.3048)
			(end 0.67945 -0.3048)
			(stroke
				(width 0.1)
				(type default)
			)
			(layer "F.Fab")
		)
		(fp_line
			(start 0.67945 -0.3048)
			(end 0.67945 0.3048)
			(stroke
				(width 0.1)
				(type default)
			)
			(layer "F.Fab")
		)
		(fp_line
			(start -0.67945 -0.305054)
			(end -0.12065 -0.305054)
			(stroke
				(width 0.1)
				(type default)
			)
			(layer "F.Fab")
		)
		(fp_line
			(start -0.12065 -0.305054)
			(end -0.12065 -0.2794)
			(stroke
				(width 0.1)
				(type default)
			)
			(layer "F.Fab")
		)
		(pad "1" smd circle
			(at -0.40005 0 270)
			(size 0 0)
			(layers "F.Cu" "F.Mask" "F.Paste")
			(net "PRSNT_CABLE_GPU_A2_ISO_N")
		)
		(pad "2" smd circle
			(at 0.40005 0 270)
			(size 0 0)
			(layers "F.Cu" "F.Mask" "F.Paste")
			(net "PRSNT_CABLE_GPU_A2_ISO_R1_N")
		)
	)
	(footprint ""
		(layer "F.Cu")
		(at 84.074 -69.596)
		(property "Reference" "U34"
			(at -2.032 -2.377948 0)
			(unlocked yes)
			(layer "F.SilkS")
			(effects
				(font
					(size 0.7874 0.5842)
					(thickness 0.1524)
				)
				(justify left)
			)
		)
		(property "Value" ""
			(at 0 0 0)
			(layer "F.Fab")
			(effects
				(font
					(size 1.27 1.27)
				)
			)
		)
		(duplicate_pad_numbers_are_jumpers no)
		(fp_line
			(start -2.0574 -1.651)
			(end -0.381 -1.651)
			(stroke
				(width 0.1524)
				(type default)
			)
			(layer "F.SilkS")
		)
		(fp_line
			(start -2.0574 1.651)
			(end -2.0574 -1.651)
			(stroke
				(width 0.1524)
				(type default)
			)
			(layer "F.SilkS")
		)
		(fp_line
			(start -0.381 -1.651)
			(end 0 -1.016)
			(stroke
				(width 0.1524)
				(type default)
			)
			(layer "F.SilkS")
		)
		(fp_line
			(start 0 -1.016)
			(end 0.381 -1.651)
			(stroke
				(width 0.1524)
				(type default)
			)
			(layer "F.SilkS")
		)
		(fp_line
			(start 0.381 -1.651)
			(end 2.0574 -1.651)
			(stroke
				(width 0.1524)
				(type default)
			)
			(layer "F.SilkS")
		)
		(fp_line
			(start 2.0574 -1.651)
			(end 2.0574 1.651)
			(stroke
				(width 0.1524)
				(type default)
			)
			(layer "F.SilkS")
		)
		(fp_line
			(start 2.0574 1.651)
			(end -2.0574 1.651)
			(stroke
				(width 0.1524)
				(type default)
			)
			(layer "F.SilkS")
		)
		(fp_poly
			(pts
				(xy -2.71272 -0.719328) (xy -2.71272 -1.344168) (xy -2.159 -1.016)
			)
			(stroke
				(width 0)
				(type default)
			)
			(fill yes)
			(layer "F.SilkS")
		)
		(fp_line
			(start -1.599946 -1.199896)
			(end -0.899922 -1.199896)
			(stroke
				(width 0.1)
				(type default)
			)
			(layer "F.Fab")
		)
		(fp_line
			(start -1.599946 1.199896)
			(end -1.599946 -1.199896)
			(stroke
				(width 0.1)
				(type default)
			)
			(layer "F.Fab")
		)
		(fp_line
			(start -0.899922 -1.549908)
			(end 0.899922 -1.549908)
			(stroke
				(width 0.1)
				(type default)
			)
			(layer "F.Fab")
		)
		(fp_line
			(start -0.899922 -1.199896)
			(end -0.899922 -1.549908)
			(stroke
				(width 0.1)
				(type default)
			)
			(layer "F.Fab")
		)
		(fp_line
			(start -0.899922 1.199896)
			(end -1.599946 1.199896)
			(stroke
				(width 0.1)
				(type default)
			)
			(layer "F.Fab")
		)
		(fp_line
			(start -0.899922 1.549908)
			(end -0.899922 1.199896)
			(stroke
				(width 0.1)
				(type default)
			)
			(layer "F.Fab")
		)
		(fp_line
			(start 0.899922 -1.549908)
			(end 0.899922 -1.199896)
			(stroke
				(width 0.1)
				(type default)
			)
			(layer "F.Fab")
		)
		(fp_line
			(start 0.899922 -1.199896)
			(end 1.599946 -1.199896)
			(stroke
				(width 0.1)
				(type default)
			)
			(layer "F.Fab")
		)
		(fp_line
			(start 0.899922 1.199896)
			(end 0.899922 1.549908)
			(stroke
				(width 0.1)
				(type default)
			)
			(layer "F.Fab")
		)
		(fp_line
			(start 0.899922 1.549908)
			(end -0.899922 1.549908)
			(stroke
				(width 0.1)
				(type default)
			)
			(layer "F.Fab")
		)
		(fp_line
			(start 1.599946 -1.199896)
			(end 1.599946 1.199896)
			(stroke
				(width 0.1)
				(type default)
			)
			(layer "F.Fab")
		)
		(fp_line
			(start 1.599946 1.199896)
			(end 0.899922 1.199896)
			(stroke
				(width 0.1)
				(type default)
			)
			(layer "F.Fab")
		)
		(fp_poly
			(pts
				(xy -2.71272 -0.719328) (xy -2.71272 -1.344168) (xy -2.159 -1.016)
			)
			(stroke
				(width 0)
				(type default)
			)
			(fill yes)
			(layer "F.Fab")
		)
		(pad "1" smd rect
			(at -1.225042 -0.94996 270)
			(size 0.5588 1.3462)
			(layers "F.Cu" "F.Mask" "F.Paste")
			(net "Net_10852")
		)
		(pad "2" smd rect
			(at -1.225042 0 270)
			(size 0.5588 1.3462)
			(layers "F.Cu" "F.Mask" "F.Paste")
			(net "OCP_V3_2_P3V3_R2_PWRGD")
		)
		(pad "3" smd rect
			(at -1.225042 0.94996 270)
			(size 0.5588 1.3462)
			(layers "F.Cu" "F.Mask" "F.Paste")
			(net "GND")
		)
		(pad "4" smd rect
			(at 1.225042 0.94996 270)
			(size 0.5588 1.3462)
			(layers "F.Cu" "F.Mask" "F.Paste")
			(net "OCP_V3_2_P3V3_PLD_PWRGD")
		)
		(pad "5" smd rect
			(at 1.225042 -0.94996 270)
			(size 0.5588 1.3462)
			(layers "F.Cu" "F.Mask" "F.Paste")
			(net "P3V3_AUX")
		)
	)
	(footprint ""
		(layer "F.Cu")
		(at 35.821112 -368.455448 90)
		(property "Reference" "PC29"
			(at 0 0 90)
			(layer "F.SilkS")
			(hide yes)
			(effects
				(font
					(size 1.27 1.27)
				)
			)
		)
		(property "Value" ""
			(at 0 0 90)
			(layer "F.Fab")
			(effects
				(font
					(size 1.27 1.27)
				)
			)
		)
		(duplicate_pad_numbers_are_jumpers no)
		(fp_line
			(start 0.7874 -0.4064)
			(end 0.7874 0.4064)
			(stroke
				(width 0.1524)
				(type default)
			)
			(layer "F.SilkS")
		)
		(fp_line
			(start -0.7874 -0.4064)
			(end 0.7874 -0.4064)
			(stroke
				(width 0.1524)
				(type default)
			)
			(layer "F.SilkS")
		)
		(fp_line
			(start 0.7874 0.4064)
			(end -0.7874 0.4064)
			(stroke
				(width 0.1524)
				(type default)
			)
			(layer "F.SilkS")
		)
		(fp_line
			(start -0.7874 0.4064)
			(end -0.7874 -0.4064)
			(stroke
				(width 0.1524)
				(type default)
			)
			(layer "F.SilkS")
		)
		(fp_line
			(start -0.12065 -0.305054)
			(end -0.12065 -0.2794)
			(stroke
				(width 0.1)
				(type default)
			)
			(layer "F.Fab")
		)
		(fp_line
			(start -0.67945 -0.305054)
			(end -0.12065 -0.305054)
			(stroke
				(width 0.1)
				(type default)
			)
			(layer "F.Fab")
		)
		(fp_line
			(start 0.67945 -0.3048)
			(end 0.67945 0.3048)
			(stroke
				(width 0.1)
				(type default)
			)
			(layer "F.Fab")
		)
		(fp_line
			(start 0.12065 -0.3048)
			(end 0.67945 -0.3048)
			(stroke
				(width 0.1)
				(type default)
			)
			(layer "F.Fab")
		)
		(fp_line
			(start 0.12065 -0.2794)
			(end 0.12065 -0.3048)
			(stroke
				(width 0.1)
				(type default)
			)
			(layer "F.Fab")
		)
		(fp_line
			(start -0.12065 -0.2794)
			(end 0.12065 -0.2794)
			(stroke
				(width 0.1)
				(type default)
			)
			(layer "F.Fab")
		)
		(fp_line
			(start 0.120396 0.2794)
			(end -0.12065 0.2794)
			(stroke
				(width 0.1)
				(type default)
			)
			(layer "F.Fab")
		)
		(fp_line
			(start -0.12065 0.2794)
			(end -0.12065 0.3048)
			(stroke
				(width 0.1)
				(type default)
			)
			(layer "F.Fab")
		)
		(fp_line
			(start 0.67945 0.3048)
			(end 0.120396 0.3048)
			(stroke
				(width 0.1)
				(type default)
			)
			(layer "F.Fab")
		)
		(fp_line
			(start 0.120396 0.3048)
			(end 0.120396 0.2794)
			(stroke
				(width 0.1)
				(type default)
			)
			(layer "F.Fab")
		)
		(fp_line
			(start -0.12065 0.3048)
			(end -0.67945 0.3048)
			(stroke
				(width 0.1)
				(type default)
			)
			(layer "F.Fab")
		)
		(fp_line
			(start -0.67945 0.3048)
			(end -0.67945 -0.305054)
			(stroke
				(width 0.1)
				(type default)
			)
			(layer "F.Fab")
		)
		(pad "1" smd circle
			(at -0.40005 0 90)
			(size 0 0)
			(layers "F.Cu" "F.Mask" "F.Paste")
			(net "PVDDCR_CPU1_P1_VCC")
		)
		(pad "2" smd circle
			(at 0.40005 0 90)
			(size 0 0)
			(layers "F.Cu" "F.Mask" "F.Paste")
			(net "GND")
		)
	)
)
